FILE_TYPE = MULTI_PHYS_TABLE;

PART 'ADC128D818CIMTXNOPB'

{========================================================================================}
:VALUE                  | PART_TYPE | MATERIAL | PART_NUMBER    = STANDARD    | LIFECYCLE     | PART_NUMBER   | JEDEC_TYPE  | DESCRIPTION                                | MANUFTR | MANUF_PN               | RD_CMPLS_LVL | CMPLS_LVL | FROM_PJ    | CLASS | DIP_SMD | DATA                          | EE_CHECK_LIST | FP_ECN | PSL | CREATOR | STATUS | CREATEDAY  ;
{========================================================================================}
 'ADC128D818CIMTX/NOPB' | 'SMLF'    | 'IC'     | 'AL000128K00'(!) = ''               | ''               | 'AL000128K00' |'TSSOP16XC'| 'IC OTHER(16P)ADC128D818CIMTX/NOPB(TSSOP)' | 'TIC'   | 'ADC128D818CIMTX/NOPB' | 'EP(V1)'     | ''        | 'S1U-OWEN' | 'IC'  | ''      | 'TIC_ADC128D818CIMTXNOPB.pdf' | ''            | ''     | ''  | ''      | ''     | '20150604'
 'ADC128D818CIMTX/NOPB' | 'SMLF'    | 'EMPTY'  | 'AL000128K00'(!) = ''               | ''               | 'AL000128K00' |'TSSOP16XC'| 'IC OTHER(16P)ADC128D818CIMTX/NOPB(TSSOP)' | 'TIC'   | 'ADC128D818CIMTX/NOPB' | 'EP(V1)'     | ''        | 'S1U-OWEN' | 'IC'  | ''      | 'TIC_ADC128D818CIMTXNOPB.pdf' | ''            | ''     | ''  | ''      | ''     | '20150604'

END_PART

END.

